(kicad_pcb
	(version 20260206)
	(generator "pcbnew")
	(generator_version "10.0")
	(general
		(thickness 1.6)
		(legacy_teardrops no)
	)
	(paper "A4")
	(title_block
		(title "04192023_DAF0TMB3IC0_F0TG_MB_C_brd_V02_OCP.brd")
		(comment 1 "Grand Teton / footprints 4355-4359 of 8354")
	)
	(layers
		(0 "F.Cu" signal "TOP")
		(4 "In1.Cu" signal "GND")
		(6 "In2.Cu" signal "IN1")
		(8 "In3.Cu" signal "GND1")
		(10 "In4.Cu" signal "IN2")
		(12 "In5.Cu" signal "GND2")
		(14 "In6.Cu" signal "IN3")
		(16 "In7.Cu" signal "GND3")
		(18 "In8.Cu" signal "VCC")
		(20 "In9.Cu" signal "VCC1")
		(22 "In10.Cu" signal "GND4")
		(24 "In11.Cu" signal "IN4")
		(26 "In12.Cu" signal "GND5")
		(28 "In13.Cu" signal "IN5")
		(30 "In14.Cu" signal "GND6")
		(32 "In15.Cu" signal "IN6")
		(34 "In16.Cu" signal "GND7")
		(2 "B.Cu" signal "BOTTOM")
		(9 "F.Adhes" user "F.Adhesive")
		(11 "B.Adhes" user "B.Adhesive")
		(13 "F.Paste" user "Package Geometry/Pastemask Top")
		(15 "B.Paste" user "Package Geometry/Pastemask Bottom")
		(5 "F.SilkS" user "Ref Des/Silkscreen Top")
		(7 "B.SilkS" user "Ref Des/Silkscreen Bottom")
		(1 "F.Mask" user "Board Geometry/Soldermask Top")
		(3 "B.Mask" user "Board Geometry/Soldermask Bottom")
		(17 "Dwgs.User" user "User.Drawings")
		(19 "Cmts.User" user "User.Comments")
		(21 "Eco1.User" user "User.Eco1")
		(23 "Eco2.User" user "User.Eco2")
		(25 "Edge.Cuts" user "Board Geometry/Outline")
		(27 "Margin" user)
		(31 "F.CrtYd" user "Package Geometry/Place Bound Top")
		(29 "B.CrtYd" user "Package Geometry/Place Bound Bottom")
		(35 "F.Fab" user "Ref Des/Assembly Top")
		(33 "B.Fab" user "Ref Des/Assembly Bottom")
	)
	(footprint ""
		(layer "F.Cu")
		(at 197.269608 -126.833376)
		(property "Reference" "R2847"
			(at 0 0 0)
			(layer "F.SilkS")
			(hide yes)
			(effects
				(font
					(size 1.27 1.27)
				)
			)
		)
		(property "Value" ""
			(at 0 0 0)
			(layer "F.Fab")
			(effects
				(font
					(size 1.27 1.27)
				)
			)
		)
		(duplicate_pad_numbers_are_jumpers no)
		(fp_line
			(start -0.7874 -0.4064)
			(end 0.7874 -0.4064)
			(stroke
				(width 0.1524)
				(type default)
			)
			(layer "F.SilkS")
		)
		(fp_line
			(start -0.7874 0.4064)
			(end -0.7874 -0.4064)
			(stroke
				(width 0.1524)
				(type default)
			)
			(layer "F.SilkS")
		)
		(fp_line
			(start 0.7874 -0.4064)
			(end 0.7874 0.4064)
			(stroke
				(width 0.1524)
				(type default)
			)
			(layer "F.SilkS")
		)
		(fp_line
			(start 0.7874 0.4064)
			(end -0.7874 0.4064)
			(stroke
				(width 0.1524)
				(type default)
			)
			(layer "F.SilkS")
		)
		(fp_line
			(start -0.67945 -0.305054)
			(end -0.12065 -0.305054)
			(stroke
				(width 0.1)
				(type default)
			)
			(layer "F.Fab")
		)
		(fp_line
			(start -0.67945 0.3048)
			(end -0.67945 -0.305054)
			(stroke
				(width 0.1)
				(type default)
			)
			(layer "F.Fab")
		)
		(fp_line
			(start -0.12065 -0.305054)
			(end -0.12065 -0.2794)
			(stroke
				(width 0.1)
				(type default)
			)
			(layer "F.Fab")
		)
		(fp_line
			(start -0.12065 -0.2794)
			(end 0.12065 -0.2794)
			(stroke
				(width 0.1)
				(type default)
			)
			(layer "F.Fab")
		)
		(fp_line
			(start -0.12065 0.2794)
			(end -0.12065 0.3048)
			(stroke
				(width 0.1)
				(type default)
			)
			(layer "F.Fab")
		)
		(fp_line
			(start -0.12065 0.3048)
			(end -0.67945 0.3048)
			(stroke
				(width 0.1)
				(type default)
			)
			(layer "F.Fab")
		)
		(fp_line
			(start 0.120396 0.2794)
			(end -0.12065 0.2794)
			(stroke
				(width 0.1)
				(type default)
			)
			(layer "F.Fab")
		)
		(fp_line
			(start 0.120396 0.3048)
			(end 0.120396 0.2794)
			(stroke
				(width 0.1)
				(type default)
			)
			(layer "F.Fab")
		)
		(fp_line
			(start 0.12065 -0.3048)
			(end 0.67945 -0.3048)
			(stroke
				(width 0.1)
				(type default)
			)
			(layer "F.Fab")
		)
		(fp_line
			(start 0.12065 -0.2794)
			(end 0.12065 -0.3048)
			(stroke
				(width 0.1)
				(type default)
			)
			(layer "F.Fab")
		)
		(fp_line
			(start 0.67945 -0.3048)
			(end 0.67945 0.3048)
			(stroke
				(width 0.1)
				(type default)
			)
			(layer "F.Fab")
		)
		(fp_line
			(start 0.67945 0.3048)
			(end 0.120396 0.3048)
			(stroke
				(width 0.1)
				(type default)
			)
			(layer "F.Fab")
		)
		(pad "1" smd circle
			(at -0.40005 0)
			(size 0 0)
			(layers "F.Cu" "F.Mask" "F.Paste")
			(net "RST_BMC_FROM_SWB_ISO_R_N")
		)
		(pad "2" smd circle
			(at 0.40005 0)
			(size 0 0)
			(layers "F.Cu" "F.Mask" "F.Paste")
			(net "RST_BMC_FROM_SWB_ISO_N")
		)
	)
	(footprint ""
		(layer "F.Cu")
		(at 355.274372 -164.844222 -90)
		(property "Reference" "PR354"
			(at 0 0 270)
			(layer "F.SilkS")
			(hide yes)
			(effects
				(font
					(size 1.27 1.27)
				)
			)
		)
		(property "Value" ""
			(at 0 0 270)
			(layer "F.Fab")
			(effects
				(font
					(size 1.27 1.27)
				)
			)
		)
		(duplicate_pad_numbers_are_jumpers no)
		(fp_line
			(start -0.7874 0.4064)
			(end -0.7874 -0.4064)
			(stroke
				(width 0.1524)
				(type default)
			)
			(layer "F.SilkS")
		)
		(fp_line
			(start 0.7874 0.4064)
			(end -0.7874 0.4064)
			(stroke
				(width 0.1524)
				(type default)
			)
			(layer "F.SilkS")
		)
		(fp_line
			(start -0.7874 -0.4064)
			(end 0.7874 -0.4064)
			(stroke
				(width 0.1524)
				(type default)
			)
			(layer "F.SilkS")
		)
		(fp_line
			(start 0.7874 -0.4064)
			(end 0.7874 0.4064)
			(stroke
				(width 0.1524)
				(type default)
			)
			(layer "F.SilkS")
		)
		(fp_line
			(start -0.67945 0.3048)
			(end -0.67945 -0.305054)
			(stroke
				(width 0.1)
				(type default)
			)
			(layer "F.Fab")
		)
		(fp_line
			(start -0.12065 0.3048)
			(end -0.67945 0.3048)
			(stroke
				(width 0.1)
				(type default)
			)
			(layer "F.Fab")
		)
		(fp_line
			(start 0.120396 0.3048)
			(end 0.120396 0.2794)
			(stroke
				(width 0.1)
				(type default)
			)
			(layer "F.Fab")
		)
		(fp_line
			(start 0.67945 0.3048)
			(end 0.120396 0.3048)
			(stroke
				(width 0.1)
				(type default)
			)
			(layer "F.Fab")
		)
		(fp_line
			(start -0.12065 0.2794)
			(end -0.12065 0.3048)
			(stroke
				(width 0.1)
				(type default)
			)
			(layer "F.Fab")
		)
		(fp_line
			(start 0.120396 0.2794)
			(end -0.12065 0.2794)
			(stroke
				(width 0.1)
				(type default)
			)
			(layer "F.Fab")
		)
		(fp_line
			(start -0.12065 -0.2794)
			(end 0.12065 -0.2794)
			(stroke
				(width 0.1)
				(type default)
			)
			(layer "F.Fab")
		)
		(fp_line
			(start 0.12065 -0.2794)
			(end 0.12065 -0.3048)
			(stroke
				(width 0.1)
				(type default)
			)
			(layer "F.Fab")
		)
		(fp_line
			(start 0.12065 -0.3048)
			(end 0.67945 -0.3048)
			(stroke
				(width 0.1)
				(type default)
			)
			(layer "F.Fab")
		)
		(fp_line
			(start 0.67945 -0.3048)
			(end 0.67945 0.3048)
			(stroke
				(width 0.1)
				(type default)
			)
			(layer "F.Fab")
		)
		(fp_line
			(start -0.67945 -0.305054)
			(end -0.12065 -0.305054)
			(stroke
				(width 0.1)
				(type default)
			)
			(layer "F.Fab")
		)
		(fp_line
			(start -0.12065 -0.305054)
			(end -0.12065 -0.2794)
			(stroke
				(width 0.1)
				(type default)
			)
			(layer "F.Fab")
		)
		(pad "1" smd circle
			(at -0.40005 0 270)
			(size 0 0)
			(layers "F.Cu" "F.Mask" "F.Paste")
			(net "SW_PVDDCR_CPU0_P0_BOOT5")
		)
		(pad "2" smd circle
			(at 0.40005 0 270)
			(size 0 0)
			(layers "F.Cu" "F.Mask" "F.Paste")
			(net "SW_PVDDCR_CPU0_P0_BOOT5_RC")
		)
	)
	(footprint ""
		(layer "F.Cu")
		(at 118.491 -425.704)
		(property "Reference" "R3457"
			(at 0 0 0)
			(layer "F.SilkS")
			(hide yes)
			(effects
				(font
					(size 1.27 1.27)
				)
			)
		)
		(property "Value" ""
			(at 0 0 0)
			(layer "F.Fab")
			(effects
				(font
					(size 1.27 1.27)
				)
			)
		)
		(duplicate_pad_numbers_are_jumpers no)
		(fp_line
			(start -0.7874 -0.4064)
			(end 0.7874 -0.4064)
			(stroke
				(width 0.1524)
				(type default)
			)
			(layer "F.SilkS")
		)
		(fp_line
			(start -0.7874 0.4064)
			(end -0.7874 -0.4064)
			(stroke
				(width 0.1524)
				(type default)
			)
			(layer "F.SilkS")
		)
		(fp_line
			(start 0.7874 -0.4064)
			(end 0.7874 0.4064)
			(stroke
				(width 0.1524)
				(type default)
			)
			(layer "F.SilkS")
		)
		(fp_line
			(start 0.7874 0.4064)
			(end -0.7874 0.4064)
			(stroke
				(width 0.1524)
				(type default)
			)
			(layer "F.SilkS")
		)
		(fp_line
			(start -0.67945 -0.305054)
			(end -0.12065 -0.305054)
			(stroke
				(width 0.1)
				(type default)
			)
			(layer "F.Fab")
		)
		(fp_line
			(start -0.67945 0.3048)
			(end -0.67945 -0.305054)
			(stroke
				(width 0.1)
				(type default)
			)
			(layer "F.Fab")
		)
		(fp_line
			(start -0.12065 -0.305054)
			(end -0.12065 -0.2794)
			(stroke
				(width 0.1)
				(type default)
			)
			(layer "F.Fab")
		)
		(fp_line
			(start -0.12065 -0.2794)
			(end 0.12065 -0.2794)
			(stroke
				(width 0.1)
				(type default)
			)
			(layer "F.Fab")
		)
		(fp_line
			(start -0.12065 0.2794)
			(end -0.12065 0.3048)
			(stroke
				(width 0.1)
				(type default)
			)
			(layer "F.Fab")
		)
		(fp_line
			(start -0.12065 0.3048)
			(end -0.67945 0.3048)
			(stroke
				(width 0.1)
				(type default)
			)
			(layer "F.Fab")
		)
		(fp_line
			(start 0.120396 0.2794)
			(end -0.12065 0.2794)
			(stroke
				(width 0.1)
				(type default)
			)
			(layer "F.Fab")
		)
		(fp_line
			(start 0.120396 0.3048)
			(end 0.120396 0.2794)
			(stroke
				(width 0.1)
				(type default)
			)
			(layer "F.Fab")
		)
		(fp_line
			(start 0.12065 -0.3048)
			(end 0.67945 -0.3048)
			(stroke
				(width 0.1)
				(type default)
			)
			(layer "F.Fab")
		)
		(fp_line
			(start 0.12065 -0.2794)
			(end 0.12065 -0.3048)
			(stroke
				(width 0.1)
				(type default)
			)
			(layer "F.Fab")
		)
		(fp_line
			(start 0.67945 -0.3048)
			(end 0.67945 0.3048)
			(stroke
				(width 0.1)
				(type default)
			)
			(layer "F.Fab")
		)
		(fp_line
			(start 0.67945 0.3048)
			(end 0.120396 0.3048)
			(stroke
				(width 0.1)
				(type default)
			)
			(layer "F.Fab")
		)
		(pad "1" smd circle
			(at -0.40005 0)
			(size 0 0)
			(layers "F.Cu" "F.Mask" "F.Paste")
			(net "GPU_BASE_STBY_EN_BUF_R")
		)
		(pad "2" smd circle
			(at 0.40005 0)
			(size 0 0)
			(layers "F.Cu" "F.Mask" "F.Paste")
			(net "GND")
		)
	)
	(footprint ""
		(layer "F.Cu")
		(at 113.105946 -259.845302)
		(property "Reference" "C2279"
			(at 0 0 0)
			(layer "F.SilkS")
			(hide yes)
			(effects
				(font
					(size 1.27 1.27)
				)
			)
		)
		(property "Value" ""
			(at 0 0 0)
			(layer "F.Fab")
			(effects
				(font
					(size 1.27 1.27)
				)
			)
		)
		(duplicate_pad_numbers_are_jumpers no)
		(fp_line
			(start -0.7874 -0.4064)
			(end 0.7874 -0.4064)
			(stroke
				(width 0.1524)
				(type default)
			)
			(layer "F.SilkS")
		)
		(fp_line
			(start -0.7874 0.4064)
			(end -0.7874 -0.4064)
			(stroke
				(width 0.1524)
				(type default)
			)
			(layer "F.SilkS")
		)
		(fp_line
			(start 0.7874 -0.4064)
			(end 0.7874 0.4064)
			(stroke
				(width 0.1524)
				(type default)
			)
			(layer "F.SilkS")
		)
		(fp_line
			(start 0.7874 0.4064)
			(end -0.7874 0.4064)
			(stroke
				(width 0.1524)
				(type default)
			)
			(layer "F.SilkS")
		)
		(fp_line
			(start -0.67945 -0.305054)
			(end -0.12065 -0.305054)
			(stroke
				(width 0.1)
				(type default)
			)
			(layer "F.Fab")
		)
		(fp_line
			(start -0.67945 0.3048)
			(end -0.67945 -0.305054)
			(stroke
				(width 0.1)
				(type default)
			)
			(layer "F.Fab")
		)
		(fp_line
			(start -0.12065 -0.305054)
			(end -0.12065 -0.2794)
			(stroke
				(width 0.1)
				(type default)
			)
			(layer "F.Fab")
		)
		(fp_line
			(start -0.12065 -0.2794)
			(end 0.12065 -0.2794)
			(stroke
				(width 0.1)
				(type default)
			)
			(layer "F.Fab")
		)
		(fp_line
			(start -0.12065 0.2794)
			(end -0.12065 0.3048)
			(stroke
				(width 0.1)
				(type default)
			)
			(layer "F.Fab")
		)
		(fp_line
			(start -0.12065 0.3048)
			(end -0.67945 0.3048)
			(stroke
				(width 0.1)
				(type default)
			)
			(layer "F.Fab")
		)
		(fp_line
			(start 0.120396 0.2794)
			(end -0.12065 0.2794)
			(stroke
				(width 0.1)
				(type default)
			)
			(layer "F.Fab")
		)
		(fp_line
			(start 0.120396 0.3048)
			(end 0.120396 0.2794)
			(stroke
				(width 0.1)
				(type default)
			)
			(layer "F.Fab")
		)
		(fp_line
			(start 0.12065 -0.3048)
			(end 0.67945 -0.3048)
			(stroke
				(width 0.1)
				(type default)
			)
			(layer "F.Fab")
		)
		(fp_line
			(start 0.12065 -0.2794)
			(end 0.12065 -0.3048)
			(stroke
				(width 0.1)
				(type default)
			)
			(layer "F.Fab")
		)
		(fp_line
			(start 0.67945 -0.3048)
			(end 0.67945 0.3048)
			(stroke
				(width 0.1)
				(type default)
			)
			(layer "F.Fab")
		)
		(fp_line
			(start 0.67945 0.3048)
			(end 0.120396 0.3048)
			(stroke
				(width 0.1)
				(type default)
			)
			(layer "F.Fab")
		)
		(pad "1" smd circle
			(at -0.40005 0)
			(size 0 0)
			(layers "F.Cu" "F.Mask" "F.Paste")
			(net "PVDD11_S3_P1")
		)
		(pad "2" smd circle
			(at 0.40005 0)
			(size 0 0)
			(layers "F.Cu" "F.Mask" "F.Paste")
			(net "GND")
		)
	)
	(footprint ""
		(layer "F.Cu")
		(at 94.681548 -352.475038)
		(property "Reference" "PC375"
			(at 0 0 0)
			(layer "F.SilkS")
			(hide yes)
			(effects
				(font
					(size 1.27 1.27)
				)
			)
		)
		(property "Value" ""
			(at 0 0 0)
			(layer "F.Fab")
			(effects
				(font
					(size 1.27 1.27)
				)
			)
		)
		(duplicate_pad_numbers_are_jumpers no)
		(fp_line
			(start -0.7874 -0.4064)
			(end 0.7874 -0.4064)
			(stroke
				(width 0.1524)
				(type default)
			)
			(layer "F.SilkS")
		)
		(fp_line
			(start -0.7874 0.4064)
			(end -0.7874 -0.4064)
			(stroke
				(width 0.1524)
				(type default)
			)
			(layer "F.SilkS")
		)
		(fp_line
			(start 0.7874 -0.4064)
			(end 0.7874 0.4064)
			(stroke
				(width 0.1524)
				(type default)
			)
			(layer "F.SilkS")
		)
		(fp_line
			(start 0.7874 0.4064)
			(end -0.7874 0.4064)
			(stroke
				(width 0.1524)
				(type default)
			)
			(layer "F.SilkS")
		)
		(fp_line
			(start -0.67945 -0.305054)
			(end -0.12065 -0.305054)
			(stroke
				(width 0.1)
				(type default)
			)
			(layer "F.Fab")
		)
		(fp_line
			(start -0.67945 0.3048)
			(end -0.67945 -0.305054)
			(stroke
				(width 0.1)
				(type default)
			)
			(layer "F.Fab")
		)
		(fp_line
			(start -0.12065 -0.305054)
			(end -0.12065 -0.2794)
			(stroke
				(width 0.1)
				(type default)
			)
			(layer "F.Fab")
		)
		(fp_line
			(start -0.12065 -0.2794)
			(end 0.12065 -0.2794)
			(stroke
				(width 0.1)
				(type default)
			)
			(layer "F.Fab")
		)
		(fp_line
			(start -0.12065 0.2794)
			(end -0.12065 0.3048)
			(stroke
				(width 0.1)
				(type default)
			)
			(layer "F.Fab")
		)
		(fp_line
			(start -0.12065 0.3048)
			(end -0.67945 0.3048)
			(stroke
				(width 0.1)
				(type default)
			)
			(layer "F.Fab")
		)
		(fp_line
			(start 0.120396 0.2794)
			(end -0.12065 0.2794)
			(stroke
				(width 0.1)
				(type default)
			)
			(layer "F.Fab")
		)
		(fp_line
			(start 0.120396 0.3048)
			(end 0.120396 0.2794)
			(stroke
				(width 0.1)
				(type default)
			)
			(layer "F.Fab")
		)
		(fp_line
			(start 0.12065 -0.3048)
			(end 0.67945 -0.3048)
			(stroke
				(width 0.1)
				(type default)
			)
			(layer "F.Fab")
		)
		(fp_line
			(start 0.12065 -0.2794)
			(end 0.12065 -0.3048)
			(stroke
				(width 0.1)
				(type default)
			)
			(layer "F.Fab")
		)
		(fp_line
			(start 0.67945 -0.3048)
			(end 0.67945 0.3048)
			(stroke
				(width 0.1)
				(type default)
			)
			(layer "F.Fab")
		)
		(fp_line
			(start 0.67945 0.3048)
			(end 0.120396 0.3048)
			(stroke
				(width 0.1)
				(type default)
			)
			(layer "F.Fab")
		)
		(pad "1" smd circle
			(at -0.40005 0)
			(size 0 0)
			(layers "F.Cu" "F.Mask" "F.Paste")
			(net "P12V_AUX")
		)
		(pad "2" smd circle
			(at 0.40005 0)
			(size 0 0)
			(layers "F.Cu" "F.Mask" "F.Paste")
			(net "GND")
		)
	)
)
